# S9S_MB_2U (Grand Teton) — schematic netlist excerpt (pin names and nets, part order shuffled) for the footprints in the layout excerpt that follows; sources: Cadence DE-HDL packaged netlist, KiCad conversion of 03242023_DA0F0TMBIJ0_F0T_Motherboard_J_brd_V01_OCP.brd

R326  Q_RES  10K 1% CHIP  pkg 0402LF  page 80 : A = P3V3_AUX ; B = PU_S3M_CPU1_CPLD_CONFD
PC1575  Q_CAPP  330UF 2V 35% SPCAP  pkg SMLF  page 275 : A = PVCCINFAON_CPU0 ; B = GND

(kicad_pcb
	(version 20260206)
	(generator "pcbnew")
	(generator_version "10.0")
	(general
		(thickness 1.6)
		(legacy_teardrops no)
	)
	(paper "A4")
	(title_block
		(title "03242023_DA0F0TMBIJ0_F0T_Motherboard_J_brd_V01_OCP.brd")
		(comment 1 "Grand Teton / footprints 5015-5016 of 6105")
	)
	(layers
		(0 "F.Cu" signal "TOP")
		(4 "In1.Cu" signal "GND")
		(6 "In2.Cu" signal "IN1")
		(8 "In3.Cu" signal "GND1")
		(10 "In4.Cu" signal "IN2")
		(12 "In5.Cu" signal "GND2")
		(14 "In6.Cu" signal "IN3")
		(16 "In7.Cu" signal "GND3")
		(18 "In8.Cu" signal "VCC")
		(20 "In9.Cu" signal "VCC1")
		(22 "In10.Cu" signal "GND4")
		(24 "In11.Cu" signal "IN4")
		(26 "In12.Cu" signal "GND5")
		(28 "In13.Cu" signal "IN5")
		(30 "In14.Cu" signal "GND6")
		(32 "In15.Cu" signal "IN6")
		(34 "In16.Cu" signal "GND7")
		(2 "B.Cu" signal "BOTTOM")
		(9 "F.Adhes" user "F.Adhesive")
		(11 "B.Adhes" user "B.Adhesive")
		(13 "F.Paste" user "Package Geometry/Pastemask Top")
		(15 "B.Paste" user "Package Geometry/Pastemask Bottom")
		(5 "F.SilkS" user "Ref Des/Silkscreen Top")
		(7 "B.SilkS" user "Ref Des/Silkscreen Bottom")
		(1 "F.Mask" user "Board Geometry/Soldermask Top")
		(3 "B.Mask" user "Board Geometry/Soldermask Bottom")
		(17 "Dwgs.User" user "User.Drawings")
		(19 "Cmts.User" user "User.Comments")
		(21 "Eco1.User" user "User.Eco1")
		(23 "Eco2.User" user "User.Eco2")
		(25 "Edge.Cuts" user "Board Geometry/Outline")
		(27 "Margin" user)
		(31 "F.CrtYd" user "Package Geometry/Place Bound Top")
		(29 "B.CrtYd" user "Package Geometry/Place Bound Bottom")
		(35 "F.Fab" user "Ref Des/Assembly Top")
		(33 "B.Fab" user "Ref Des/Assembly Bottom")
	)
	(footprint ""
		(layer "B.Cu")
		(at 180.514752 -192.699894 -90)
		(property "Reference" "R326"
			(at 0 0 90)
			(layer "B.SilkS")
			(hide yes)
			(effects
				(font
					(size 1.27 1.27)
				)
				(justify mirror)
			)
		)
		(property "Value" ""
			(at 0 0 90)
			(layer "B.Fab")
			(effects
				(font
					(size 1.27 1.27)
				)
				(justify mirror)
			)
		)
		(duplicate_pad_numbers_are_jumpers no)
		(fp_line
			(start -0.7874 0.4064)
			(end 0.7874 0.4064)
			(stroke
				(width 0.1524)
				(type default)
			)
			(layer "B.SilkS")
		)
		(fp_line
			(start 0.7874 0.4064)
			(end 0.7874 -0.4064)
			(stroke
				(width 0.1524)
				(type default)
			)
			(layer "B.SilkS")
		)
		(fp_line
			(start -0.7874 -0.4064)
			(end -0.7874 0.4064)
			(stroke
				(width 0.1524)
				(type default)
			)
			(layer "B.SilkS")
		)
		(fp_line
			(start 0.7874 -0.4064)
			(end -0.7874 -0.4064)
			(stroke
				(width 0.1524)
				(type default)
			)
			(layer "B.SilkS")
		)
		(fp_line
			(start -0.67945 0.3048)
			(end -0.120396 0.3048)
			(stroke
				(width 0.1)
				(type default)
			)
			(layer "B.Fab")
		)
		(fp_line
			(start -0.120396 0.3048)
			(end -0.120396 0.2794)
			(stroke
				(width 0.1)
				(type default)
			)
			(layer "B.Fab")
		)
		(fp_line
			(start 0.12065 0.3048)
			(end 0.67945 0.3048)
			(stroke
				(width 0.1)
				(type default)
			)
			(layer "B.Fab")
		)
		(fp_line
			(start 0.67945 0.3048)
			(end 0.67945 -0.305054)
			(stroke
				(width 0.1)
				(type default)
			)
			(layer "B.Fab")
		)
		(fp_line
			(start -0.120396 0.2794)
			(end 0.12065 0.2794)
			(stroke
				(width 0.1)
				(type default)
			)
			(layer "B.Fab")
		)
		(fp_line
			(start 0.12065 0.2794)
			(end 0.12065 0.3048)
			(stroke
				(width 0.1)
				(type default)
			)
			(layer "B.Fab")
		)
		(fp_line
			(start -0.12065 -0.2794)
			(end -0.12065 -0.3048)
			(stroke
				(width 0.1)
				(type default)
			)
			(layer "B.Fab")
		)
		(fp_line
			(start 0.12065 -0.2794)
			(end -0.12065 -0.2794)
			(stroke
				(width 0.1)
				(type default)
			)
			(layer "B.Fab")
		)
		(fp_line
			(start -0.67945 -0.3048)
			(end -0.67945 0.3048)
			(stroke
				(width 0.1)
				(type default)
			)
			(layer "B.Fab")
		)
		(fp_line
			(start -0.12065 -0.3048)
			(end -0.67945 -0.3048)
			(stroke
				(width 0.1)
				(type default)
			)
			(layer "B.Fab")
		)
		(fp_line
			(start 0.12065 -0.305054)
			(end 0.12065 -0.2794)
			(stroke
				(width 0.1)
				(type default)
			)
			(layer "B.Fab")
		)
		(fp_line
			(start 0.67945 -0.305054)
			(end 0.12065 -0.305054)
			(stroke
				(width 0.1)
				(type default)
			)
			(layer "B.Fab")
		)
		(pad "1" smd circle
			(at 0.40005 0 90)
			(size 0 0)
			(layers "B.Cu" "B.Mask" "B.Paste")
			(net "P3V3_AUX")
		)
		(pad "2" smd circle
			(at -0.40005 0 90)
			(size 0 0)
			(layers "B.Cu" "B.Mask" "B.Paste")
			(net "PU_S3M_CPU1_CPLD_CONFD")
		)
	)
	(footprint ""
		(layer "B.Cu")
		(at 409.284932 -170.821858 180)
		(property "Reference" "PC1575"
			(at 0 0 0)
			(layer "B.SilkS")
			(hide yes)
			(effects
				(font
					(size 1.27 1.27)
				)
				(justify mirror)
			)
		)
		(property "Value" ""
			(at 0 0 0)
			(layer "B.Fab")
			(effects
				(font
					(size 1.27 1.27)
				)
				(justify mirror)
			)
		)
		(duplicate_pad_numbers_are_jumpers no)
		(fp_line
			(start 4.84378 -2.150618)
			(end 4.842256 2.163064)
			(stroke
				(width 0.1524)
				(type default)
			)
			(layer "B.SilkS")
		)
		(fp_line
			(start 4.84378 -2.150618)
			(end 4.53898 -2.150618)
			(stroke
				(width 0.1524)
				(type default)
			)
			(layer "B.SilkS")
		)
		(fp_line
			(start 4.83108 2.150364)
			(end 4.447794 2.149348)
			(stroke
				(width 0.1524)
				(type default)
			)
			(layer "B.SilkS")
		)
		(fp_line
			(start 4.69138 -2.150618)
			(end 4.692396 2.161032)
			(stroke
				(width 0.1524)
				(type default)
			)
			(layer "B.SilkS")
		)
		(fp_line
			(start 4.53898 2.15011)
			(end 4.53898 -2.15011)
			(stroke
				(width 0.1524)
				(type default)
			)
			(layer "B.SilkS")
		)
		(fp_line
			(start 4.53898 -2.15011)
			(end -4.53898 -2.15011)
			(stroke
				(width 0.1524)
				(type default)
			)
			(layer "B.SilkS")
		)
		(fp_line
			(start 4.53898 -2.150618)
			(end 4.539742 2.152142)
			(stroke
				(width 0.1524)
				(type default)
			)
			(layer "B.SilkS")
		)
		(fp_line
			(start -4.53898 2.15011)
			(end 4.53898 2.15011)
			(stroke
				(width 0.1524)
				(type default)
			)
			(layer "B.SilkS")
		)
		(fp_line
			(start -4.53898 -2.15011)
			(end -4.53898 2.15011)
			(stroke
				(width 0.1524)
				(type default)
			)
			(layer "B.SilkS")
		)
		(fp_line
			(start 3.64998 2.15011)
			(end 3.64998 -2.15011)
			(stroke
				(width 0.1)
				(type default)
			)
			(layer "B.Fab")
		)
		(fp_line
			(start 3.64998 -2.15011)
			(end -3.64998 -2.15011)
			(stroke
				(width 0.1)
				(type default)
			)
			(layer "B.Fab")
		)
		(fp_line
			(start -3.64998 2.15011)
			(end 3.64998 2.15011)
			(stroke
				(width 0.1)
				(type default)
			)
			(layer "B.Fab")
		)
		(fp_line
			(start -3.64998 -2.15011)
			(end -3.64998 2.15011)
			(stroke
				(width 0.1)
				(type default)
			)
			(layer "B.Fab")
		)
		(fp_text user "+"
			(at 6.214872 -0.337058 180)
			(unlocked yes)
			(layer "B.SilkS")
			(effects
				(font
					(size 1.905 1.4224)
					(thickness 0.1524)
				)
				(justify left mirror)
			)
		)
		(fp_text user "-"
			(at -5.702808 0.98806 180)
			(unlocked yes)
			(layer "B.SilkS")
			(effects
				(font
					(size 1.905 1.4224)
					(thickness 0.1524)
				)
				(justify left mirror)
			)
		)
		(fp_text user "+"
			(at 6.214872 -0.337058 180)
			(unlocked yes)
			(layer "B.Fab")
			(effects
				(font
					(size 1.905 1.4224)
					(thickness 0.1524)
				)
				(justify left mirror)
			)
		)
		(fp_text user "-"
			(at -4.313174 -0.094488 180)
			(unlocked yes)
			(layer "B.Fab")
			(effects
				(font
					(size 1.905 1.4224)
					(thickness 0.1524)
				)
				(justify left mirror)
			)
		)
		(pad "1" smd rect
			(at 3.199892 0)
			(size 2.413 2.8194)
			(layers "B.Cu" "B.Mask" "B.Paste")
			(net "PVCCINFAON_CPU0")
		)
		(pad "2" smd rect
			(at -3.199892 0)
			(size 2.413 2.8194)
			(layers "B.Cu" "B.Mask" "B.Paste")
			(net "GND")
		)
	)
)
